FILE_TYPE = CONNECTIVITY;
{Allegro Design Entry HDL 17.4-2019 S026 (4007227) 1/17/2022}
"PAGE_NUMBER" = 47;
0"NC";
1"M_K_CPU1_SA_DQ<31:0>";
2"M_K_CPU1_SB_DQ<31:0>";
3"M_K_CPU1_SA_CB<7:0>";
4"M_K_CPU1_SB_CB<7:0>";
5"M_K_CPU1_SA_DQS_DP<9:0>";
6"M_K_CPU1_SA_DQS_DN<9:0>";
7"M_K_CPU1_SB_DQS_DP<9:0>";
8"M_K_CPU1_SB_DQS_DN<9:0>";
9"M_K_CPU1_SB_CA<6:0>";
10"M_K_CPU1_SA_CA<6:0>";
11"M_K_CPU1_ALERT_N";
12"M_K_CPU1_ALERT_R_N";
13"TP_M_K_CPU1_SA_TEST39K";
14"M_K_CPU1_CLK_DN<0>";
15"M_K_CPU1_CLK_DP<0>";
16"M_K_CPU1_SA_CS_N<0>";
17"M_K_CPU1_SA_CS_N<1>";
18"M_K_CPU1_SA_RSP<0>";
19"M_K_CPU1_SA_PAR";
20"M_K_CPU1_SB_CS_N<0>";
21"M_K_CPU1_SB_CS_N<1>";
22"M_K_CPU1_SB_RSP<0>";
23"M_K_CPU1_SB_PAR";
24"M_K_CPU1_RESET_N";
25"M_K_CPU1_SB_CA<6>";
26"M_K_CPU1_SA_CA<0>";
27"M_K_CPU1_SA_CA<6>";
28"M_K_CPU1_SB_CA<5>";
29"M_K_CPU1_SA_CA<5>";
30"M_K_CPU1_SB_CA<4>";
31"M_K_CPU1_SA_CA<4>";
32"M_K_CPU1_SB_CA<3>";
33"M_K_CPU1_SB_DQS_DN<9>";
34"M_K_CPU1_SA_CA<3>";
35"M_K_CPU1_SB_CA<2>";
36"M_K_CPU1_SB_DQS_DN<8>";
37"M_K_CPU1_SA_CA<2>";
38"M_K_CPU1_SB_CA<1>";
39"M_K_CPU1_SA_CA<1>";
40"M_K_CPU1_SB_CA<0>";
41"M_K_CPU1_SB_DQS_DP<9>";
42"M_K_CPU1_SB_DQS_DP<8>";
43"M_K_CPU1_SB_DQS_DN<5>";
44"M_K_CPU1_SB_DQS_DN<4>";
45"M_K_CPU1_SA_DQS_DN<9>";
46"M_K_CPU1_SB_DQS_DN<3>";
47"M_K_CPU1_SA_DQS_DN<8>";
48"M_K_CPU1_SB_DQS_DN<2>";
49"M_K_CPU1_SB_DQS_DN<1>";
50"M_K_CPU1_SB_DQS_DN<0>";
51"M_K_CPU1_SB_DQS_DN<7>";
52"M_K_CPU1_SB_DQS_DN<6>";
53"M_K_CPU1_SB_DQS_DP<7>";
54"M_K_CPU1_SB_DQS_DP<6>";
55"M_K_CPU1_SB_DQS_DP<5>";
56"M_K_CPU1_SB_DQS_DP<4>";
57"M_K_CPU1_SB_DQS_DP<3>";
58"M_K_CPU1_SB_DQS_DP<1>";
59"M_K_CPU1_SB_DQS_DP<0>";
60"M_K_CPU1_SA_DQS_DP<9>";
61"M_K_CPU1_SA_DQS_DP<8>";
62"M_K_CPU1_SB_DQS_DP<2>";
63"M_K_CPU1_SA_DQS_DN<7>";
64"M_K_CPU1_SA_DQS_DN<6>";
65"M_K_CPU1_SA_DQS_DN<5>";
66"M_K_CPU1_SA_DQS_DN<4>";
67"M_K_CPU1_SA_DQS_DN<3>";
68"M_K_CPU1_SA_DQS_DN<2>";
69"M_K_CPU1_SA_DQS_DN<1>";
70"M_K_CPU1_SA_DQS_DN<0>";
71"M_K_CPU1_SA_DQS_DP<7>";
72"M_K_CPU1_SA_DQS_DP<6>";
73"M_K_CPU1_SA_DQS_DP<5>";
74"M_K_CPU1_SA_DQS_DP<4>";
75"M_K_CPU1_SA_DQS_DP<3>";
76"M_K_CPU1_SA_DQS_DP<2>";
77"M_K_CPU1_SA_DQS_DP<1>";
78"M_K_CPU1_SA_DQS_DP<0>";
79"M_K_CPU1_SB_CB<7>";
80"M_K_CPU1_SB_CB<6>";
81"M_K_CPU1_SB_CB<5>";
82"M_K_CPU1_SB_CB<4>";
83"M_K_CPU1_SB_CB<3>";
84"M_K_CPU1_SB_CB<2>";
85"M_K_CPU1_SA_CB<7>";
86"M_K_CPU1_SB_CB<1>";
87"M_K_CPU1_SA_CB<6>";
88"M_K_CPU1_SB_CB<0>";
89"M_K_CPU1_SB_DQ<29>";
90"M_K_CPU1_SB_DQ<28>";
91"M_K_CPU1_SB_DQ<27>";
92"M_K_CPU1_SB_DQ<26>";
93"M_K_CPU1_SB_DQ<25>";
94"M_K_CPU1_SB_DQ<24>";
95"M_K_CPU1_SB_DQ<23>";
96"M_K_CPU1_SB_DQ<22>";
97"M_K_CPU1_SB_DQ<21>";
98"M_K_CPU1_SB_DQ<20>";
99"M_K_CPU1_SB_DQ<31>";
100"M_K_CPU1_SA_CB<5>";
101"M_K_CPU1_SB_DQ<30>";
102"M_K_CPU1_SA_CB<4>";
103"M_K_CPU1_SA_CB<3>";
104"M_K_CPU1_SA_CB<2>";
105"M_K_CPU1_SA_CB<1>";
106"M_K_CPU1_SA_CB<0>";
107"M_K_CPU1_SB_DQ<19>";
108"M_K_CPU1_SB_DQ<9>";
109"M_K_CPU1_SB_DQ<18>";
110"M_K_CPU1_SB_DQ<8>";
111"M_K_CPU1_SB_DQ<17>";
112"M_K_CPU1_SB_DQ<7>";
113"M_K_CPU1_SB_DQ<16>";
114"M_K_CPU1_SB_DQ<6>";
115"M_K_CPU1_SB_DQ<15>";
116"M_K_CPU1_SB_DQ<5>";
117"M_K_CPU1_SB_DQ<14>";
118"M_K_CPU1_SB_DQ<4>";
119"M_K_CPU1_SB_DQ<13>";
120"M_K_CPU1_SB_DQ<3>";
121"M_K_CPU1_SB_DQ<12>";
122"M_K_CPU1_SB_DQ<2>";
123"M_K_CPU1_SB_DQ<11>";
124"M_K_CPU1_SB_DQ<1>";
125"M_K_CPU1_SB_DQ<10>";
126"M_K_CPU1_SA_DQ<19>";
127"M_K_CPU1_SA_DQ<18>";
128"M_K_CPU1_SA_DQ<29>";
129"M_K_CPU1_SA_DQ<17>";
130"M_K_CPU1_SA_DQ<28>";
131"M_K_CPU1_SA_DQ<16>";
132"M_K_CPU1_SA_DQ<27>";
133"M_K_CPU1_SA_DQ<15>";
134"M_K_CPU1_SA_DQ<26>";
135"M_K_CPU1_SB_DQ<0>";
136"M_K_CPU1_SA_DQ<25>";
137"M_K_CPU1_SA_DQ<24>";
138"M_K_CPU1_SA_DQ<23>";
139"M_K_CPU1_SA_DQ<22>";
140"M_K_CPU1_SA_DQ<21>";
141"M_K_CPU1_SA_DQ<20>";
142"M_K_CPU1_SA_DQ<31>";
143"M_K_CPU1_SA_DQ<30>";
144"M_K_CPU1_SA_DQ<9>";
145"M_K_CPU1_SA_DQ<8>";
146"M_K_CPU1_SA_DQ<7>";
147"M_K_CPU1_SA_DQ<6>";
148"M_K_CPU1_SA_DQ<5>";
149"M_K_CPU1_SA_DQ<4>";
150"M_K_CPU1_SA_DQ<3>";
151"M_K_CPU1_SA_DQ<2>";
152"M_K_CPU1_SA_DQ<1>";
153"M_K_CPU1_SA_DQ<0>";
154"M_K_CPU1_SA_DQ<14>";
155"M_K_CPU1_SA_DQ<13>";
156"M_K_CPU1_SA_DQ<12>";
157"M_K_CPU1_SA_DQ<11>";
158"M_K_CPU1_SA_DQ<10>";
%"GENOA_SP5"
"36","(-4500,3525)","0","pure_quanta","I159";
;
LOCATION"U26"
$SEC"36"
CDS_SEC"36"
PART_TYPE"SMLF"
MATERIAL"IO"
VALUE"SOCKET6096_13568-001"
CDS_LIB"pure_quanta"
CDS_LMAN_SYM_OUTLINE"-650,2525,650,-2525"
NEEDS_NO_SIZE"TRUE"
PART_NUMBER"DGA^6000030";
"TEST39K"
$PN"BF7"13;
"MKA0_CS_L0"
$PN"AU5"16;
"MKA_CA0"
$PN"AW5"26;
"MKA_DQS_H7"
$PN"AA7"71;
"MKB_DATA9"
$PN"CJ7"108;
"MKB_DATA18"
$PN"CR5"109;
"MKB_DATA29"
$PN"DE7"89;
"MKB_DQS_H1"
$PN"CK6"58;
"MKB_DQS_L5"
$PN"CE7"43;
"MKA_DATA9"
$PN"M7"144;
"MKA_DQS_H6"
$PN"R7"72;
"MKB1_RSP_L"
$PN"BR5"0;
"MKB_DATA8"
$PN"CH6"110;
"MKB_DATA17"
$PN"CR7"111;
"MKB_DATA28"
$PN"DD6"90;
"MKB_DQS_H0"
$PN"CD6"59;
"MKB_DQS_L4"
$PN"BW7"44;
"MKA_DATA8"
$PN"L5"145;
"MKA_DQS_H5"
$PN"J7"73;
"MKA_DQS_L9"
$PN"AM7"45;
"MKB0_RSP_L"
$PN"BP6"22;
"MKB_CHECK7"
$PN"BV7"79;
"MKB_DATA7"
$PN"CH7"112;
"MKB_DATA16"
$PN"CP6"113;
"MKB_DATA27"
$PN"DB7"91;
"MKB_DQS_L3"
$PN"DC5"46;
"MKA_DATA7"
$PN"L7"146;
"MKA_DQS_H4"
$PN"AL5"74;
"MKA_DQS_L8"
$PN"AF7"47;
"MKB_CHECK6"
$PN"BU5"80;
"MKB_DATA6"
$PN"CG5"114;
"MKB_DATA15"
$PN"CP7"115;
"MKB_DATA26"
$PN"DA5"92;
"MKB_DQS_L2"
$PN"CU5"48;
"MKB_PAR"
$PN"BL7"23;
"MKA_DATA6"
$PN"K6"147;
"MKA_DQS_H3"
$PN"AE5"75;
"MKA_DQS_L7"
$PN"Y7"63;
"MKA_PAR"
$PN"BC7"19;
"MKB_CHECK5"
$PN"BU7"81;
"MKB_DATA5"
$PN"CG7"116;
"MKB_DATA14"
$PN"CN5"117;
"MKB_DATA25"
$PN"DA7"93;
"MKB_DQS_L1"
$PN"CL5"49;
"MKA_DATA5"
$PN"K7"148;
"MKA_DATA19"
$PN"W7"126;
"MKA_DQS_H2"
$PN"W5"76;
"MKA_DQS_L6"
$PN"P7"64;
"MKB_CHECK4"
$PN"BT6"82;
"MKB_DATA4"
$PN"CF6"118;
"MKB_DATA13"
$PN"CN7"119;
"MKB_DATA24"
$PN"CY6"94;
"MKB_DQS_L0"
$PN"CE5"50;
"MKA_DATA4"
$PN"J5"149;
"MKA_DATA18"
$PN"V6"127;
"MKA_DATA29"
$PN"AH7"128;
"MKA_DQS_H1"
$PN"N5"77;
"MKA_DQS_L5"
$PN"H7"65;
"MKB_CHECK3"
$PN"CB7"83;
"MKB_DATA3"
$PN"CD7"120;
"MKB_DATA12"
$PN"CM6"121;
"MKB_DATA23"
$PN"CY7"95;
"MKA1_RSP_L"
$PN"BP7"0;
"MKA_DATA3"
$PN"G7"150;
"MKA_DATA17"
$PN"V7"129;
"MKA_DATA28"
$PN"AG5"130;
"MKA_DQS_H0"
$PN"G5"78;
"MKA_DQS_L4"
$PN"AM6"66;
"MKB_CHECK2"
$PN"CA5"84;
"MKB_DATA2"
$PN"CC5"122;
"MKB_DATA11"
$PN"CK7"123;
"MKB_DATA22"
$PN"CW5"96;
"MK_ALERT_L"
$PN"AT7"12;
"MKA0_RSP_L"
$PN"BN7"18;
"MKA_CHECK7"
$PN"AR7"85;
"MKA_DATA2"
$PN"F6"151;
"MKA_DATA16"
$PN"U5"131;
"MKA_DATA27"
$PN"AE7"132;
"MKA_DQS_L3"
$PN"AF6"67;
"MKB_CHECK1"
$PN"CA7"86;
"MKB_DATA1"
$PN"CC7"124;
"MKB_DATA10"
$PN"CJ5"125;
"MKB_DATA21"
$PN"CW7"97;
"MKA_CHECK6"
$PN"AP6"87;
"MKA_DATA1"
$PN"F7"152;
"MKA_DATA15"
$PN"U7"133;
"MKA_DATA26"
$PN"AD6"134;
"MKA_DQS_L2"
$PN"Y6"68;
"MKB1_CS_L1"
$PN"BM6"0;
"MKB_CHECK0"
$PN"BY6"88;
"MKB_DATA0"
$PN"CB6"135;
"MKB_DATA20"
$PN"CV6"98;
"MKB_DATA31"
$PN"DF7"99;
"MKB_DQS_H9"
$PN"BV6"41;
"MK1_CLK_L"
$PN"BG5"0;
"MKA_CHECK5"
$PN"AP7"100;
"MKA_DATA0"
$PN"E5"153;
"MKA_DATA14"
$PN"T6"154;
"MKA_DATA25"
$PN"AD7"136;
"MKA_DQS_L1"
$PN"P6"69;
"MKB0_CS_L1"
$PN"BN5"21;
"MKB1_CS_L0"
$PN"BL5"0;
"MKB_CA6"
$PN"BK6"25;
"MKB_DATA30"
$PN"DE5"101;
"MKB_DQS_H8"
$PN"DD7"42;
"MK0_CLK_L"
$PN"BD6"14;
"MKA_CA6"
$PN"BB7"27;
"MKA_CHECK4"
$PN"AN5"102;
"MKA_DATA13"
$PN"T7"155;
"MKA_DATA24"
$PN"AC5"137;
"MKA_DQS_L0"
$PN"H6"70;
"MKB0_CS_L0"
$PN"BM7"20;
"MKB_CA5"
$PN"BK7"28;
"MKB_DQS_H7"
$PN"CV7"53;
"MKA_CA5"
$PN"BB6"29;
"MKA_CHECK3"
$PN"AL7"103;
"MKA_DATA12"
$PN"R5"156;
"MKA_DATA23"
$PN"AC7"138;
"MKB_CA4"
$PN"BJ7"30;
"MKB_DQS_H6"
$PN"CM7"54;
"MK_RESET_L"
$PN"AU7"24;
"MKA_CA4"
$PN"BA5"31;
"MKA_CHECK2"
$PN"AK6"104;
"MKA_DATA11"
$PN"N7"157;
"MKA_DATA22"
$PN"AB6"139;
"MKB_CA3"
$PN"BJ5"32;
"MKB_DQS_H5"
$PN"CF7"55;
"MKB_DQS_L9"
$PN"BW5"33;
"MK1_CLK_H"
$PN"BF6"0;
"MKA_CA3"
$PN"BA7"34;
"MKA_CHECK1"
$PN"AK7"105;
"MKA_DATA10"
$PN"M6"158;
"MKA_DATA21"
$PN"AB7"140;
"MKB_CA2"
$PN"BH6"35;
"MKB_DQS_H4"
$PN"BY7"56;
"MKB_DQS_L8"
$PN"DC7"36;
"MK0_CLK_H"
$PN"BC5"15;
"MKA1_CS_L1"
$PN"AW7"0;
"MKA_CA2"
$PN"AY7"37;
"MKA_CHECK0"
$PN"AJ5"106;
"MKA_DATA20"
$PN"AA5"141;
"MKA_DATA31"
$PN"AJ7"142;
"MKA_DQS_H9"
$PN"AN7"60;
"MKB_CA1"
$PN"BH7"38;
"MKB_DQS_H3"
$PN"DB6"57;
"MKB_DQS_L7"
$PN"CU7"51;
"MKA0_CS_L1"
$PN"AV7"17;
"MKA1_CS_L0"
$PN"AV6"0;
"MKA_CA1"
$PN"AY6"39;
"MKA_DATA30"
$PN"AH6"143;
"MKA_DQS_H8"
$PN"AG7"61;
"MKB_CA0"
$PN"BG7"40;
"MKB_DATA19"
$PN"CT7"107;
"MKB_DQS_H2"
$PN"CT6"62;
"MKB_DQS_L6"
$PN"CL7"52;
%"TAP"
"1","(-3225,5900)","0","mstr_standard","I161";
;
CDS_LIB"mstr_standard"
BODY_TYPE"PLUMBING"
HDL_TAP"TRUE";
"B \NAC \NWC"1;
"S \NAC"
BN"0"153;
%"TAP"
"1","(-3225,5850)","0","mstr_standard","I162";
;
CDS_LIB"mstr_standard"
BODY_TYPE"PLUMBING"
HDL_TAP"TRUE";
"B \NAC \NWC"1;
"S \NAC"
BN"1"152;
%"TAP"
"1","(-3225,5800)","0","mstr_standard","I163";
;
CDS_LIB"mstr_standard"
BODY_TYPE"PLUMBING"
HDL_TAP"TRUE";
"B \NAC \NWC"1;
"S \NAC"
BN"2"151;
%"TAP"
"1","(-3225,5750)","0","mstr_standard","I164";
;
CDS_LIB"mstr_standard"
BODY_TYPE"PLUMBING"
HDL_TAP"TRUE";
"B \NAC \NWC"1;
"S \NAC"
BN"3"150;
%"TAP"
"1","(-3225,5650)","0","mstr_standard","I165";
;
CDS_LIB"mstr_standard"
BODY_TYPE"PLUMBING"
HDL_TAP"TRUE";
"B \NAC \NWC"1;
"S \NAC"
BN"5"148;
%"TAP"
"1","(-3225,5700)","0","mstr_standard","I166";
;
CDS_LIB"mstr_standard"
BODY_TYPE"PLUMBING"
HDL_TAP"TRUE";
"B \NAC \NWC"1;
"S \NAC"
BN"4"149;
%"TAP"
"1","(-3225,5600)","0","mstr_standard","I167";
;
CDS_LIB"mstr_standard"
BODY_TYPE"PLUMBING"
HDL_TAP"TRUE";
"B \NAC \NWC"1;
"S \NAC"
BN"6"147;
%"TAP"
"1","(-3225,5550)","0","mstr_standard","I168";
;
CDS_LIB"mstr_standard"
BODY_TYPE"PLUMBING"
HDL_TAP"TRUE";
"B \NAC \NWC"1;
"S \NAC"
BN"7"146;
%"TAP"
"1","(-3225,5400)","0","mstr_standard","I169";
;
CDS_LIB"mstr_standard"
BODY_TYPE"PLUMBING"
HDL_TAP"TRUE";
"B \NAC \NWC"1;
"S \NAC"
BN"9"144;
%"TAP"
"1","(-3225,5450)","0","mstr_standard","I170";
;
CDS_LIB"mstr_standard"
BODY_TYPE"PLUMBING"
HDL_TAP"TRUE";
"B \NAC \NWC"1;
"S \NAC"
BN"8"145;
%"TAP"
"1","(-3225,5350)","0","mstr_standard","I171";
;
CDS_LIB"mstr_standard"
BODY_TYPE"PLUMBING"
HDL_TAP"TRUE";
"B \NAC \NWC"1;
"S \NAC"
BN"10"158;
%"TAP"
"1","(-3225,5300)","0","mstr_standard","I172";
;
CDS_LIB"mstr_standard"
BODY_TYPE"PLUMBING"
HDL_TAP"TRUE";
"B \NAC \NWC"1;
"S \NAC"
BN"11"157;
%"TAP"
"1","(-3225,5250)","0","mstr_standard","I173";
;
CDS_LIB"mstr_standard"
BODY_TYPE"PLUMBING"
HDL_TAP"TRUE";
"B \NAC \NWC"1;
"S \NAC"
BN"12"156;
%"TAP"
"1","(-3225,5200)","0","mstr_standard","I174";
;
CDS_LIB"mstr_standard"
BODY_TYPE"PLUMBING"
HDL_TAP"TRUE";
"B \NAC \NWC"1;
"S \NAC"
BN"13"155;
%"TAP"
"1","(-3225,5150)","0","mstr_standard","I175";
;
CDS_LIB"mstr_standard"
BODY_TYPE"PLUMBING"
HDL_TAP"TRUE";
"B \NAC \NWC"1;
"S \NAC"
BN"14"154;
%"TAP"
"1","(-3225,4950)","0","mstr_standard","I176";
;
CDS_LIB"mstr_standard"
BODY_TYPE"PLUMBING"
HDL_TAP"TRUE";
"B \NAC \NWC"1;
"S \NAC"
BN"17"129;
%"TAP"
"1","(-3225,5100)","0","mstr_standard","I177";
;
CDS_LIB"mstr_standard"
BODY_TYPE"PLUMBING"
HDL_TAP"TRUE";
"B \NAC \NWC"1;
"S \NAC"
BN"15"133;
%"TAP"
"1","(-3225,5000)","0","mstr_standard","I178";
;
CDS_LIB"mstr_standard"
BODY_TYPE"PLUMBING"
HDL_TAP"TRUE";
"B \NAC \NWC"1;
"S \NAC"
BN"16"131;
%"TAP"
"1","(-3225,4900)","0","mstr_standard","I179";
;
CDS_LIB"mstr_standard"
BODY_TYPE"PLUMBING"
HDL_TAP"TRUE";
"B \NAC \NWC"1;
"S \NAC"
BN"18"127;
%"TAP"
"1","(-3225,4850)","0","mstr_standard","I180";
;
CDS_LIB"mstr_standard"
BODY_TYPE"PLUMBING"
HDL_TAP"TRUE";
"B \NAC \NWC"1;
"S \NAC"
BN"19"126;
%"TAP"
"1","(-3225,4800)","0","mstr_standard","I181";
;
CDS_LIB"mstr_standard"
BODY_TYPE"PLUMBING"
HDL_TAP"TRUE";
"B \NAC \NWC"1;
"S \NAC"
BN"20"141;
%"TAP"
"1","(-3225,4750)","0","mstr_standard","I182";
;
CDS_LIB"mstr_standard"
BODY_TYPE"PLUMBING"
HDL_TAP"TRUE";
"B \NAC \NWC"1;
"S \NAC"
BN"21"140;
%"TAP"
"1","(-3225,4700)","0","mstr_standard","I183";
;
CDS_LIB"mstr_standard"
BODY_TYPE"PLUMBING"
HDL_TAP"TRUE";
"B \NAC \NWC"1;
"S \NAC"
BN"22"139;
%"TAP"
"1","(-3225,4650)","0","mstr_standard","I184";
;
CDS_LIB"mstr_standard"
BODY_TYPE"PLUMBING"
HDL_TAP"TRUE";
"B \NAC \NWC"1;
"S \NAC"
BN"23"138;
%"TAP"
"1","(-3225,4550)","0","mstr_standard","I185";
;
CDS_LIB"mstr_standard"
BODY_TYPE"PLUMBING"
HDL_TAP"TRUE";
"B \NAC \NWC"1;
"S \NAC"
BN"24"137;
%"TAP"
"1","(-3225,4500)","0","mstr_standard","I186";
;
CDS_LIB"mstr_standard"
BODY_TYPE"PLUMBING"
HDL_TAP"TRUE";
"B \NAC \NWC"1;
"S \NAC"
BN"25"136;
%"TAP"
"1","(-3225,4450)","0","mstr_standard","I187";
;
CDS_LIB"mstr_standard"
BODY_TYPE"PLUMBING"
HDL_TAP"TRUE";
"B \NAC \NWC"1;
"S \NAC"
BN"26"134;
%"TAP"
"1","(-3225,4400)","0","mstr_standard","I188";
;
CDS_LIB"mstr_standard"
BODY_TYPE"PLUMBING"
HDL_TAP"TRUE";
"B \NAC \NWC"1;
"S \NAC"
BN"27"132;
%"TAP"
"1","(-3225,4350)","0","mstr_standard","I189";
;
CDS_LIB"mstr_standard"
BODY_TYPE"PLUMBING"
HDL_TAP"TRUE";
"B \NAC \NWC"1;
"S \NAC"
BN"28"130;
%"TAP"
"1","(-3225,4300)","0","mstr_standard","I190";
;
CDS_LIB"mstr_standard"
BODY_TYPE"PLUMBING"
HDL_TAP"TRUE";
"B \NAC \NWC"1;
"S \NAC"
BN"29"128;
%"TAP"
"1","(-3225,4250)","0","mstr_standard","I191";
;
CDS_LIB"mstr_standard"
BODY_TYPE"PLUMBING"
HDL_TAP"TRUE";
"B \NAC \NWC"1;
"S \NAC"
BN"30"143;
%"TAP"
"1","(-3225,4200)","0","mstr_standard","I192";
;
CDS_LIB"mstr_standard"
BODY_TYPE"PLUMBING"
HDL_TAP"TRUE";
"B \NAC \NWC"1;
"S \NAC"
BN"31"142;
%"TAP"
"1","(-3225,4100)","0","mstr_standard","I193";
;
CDS_LIB"mstr_standard"
BODY_TYPE"PLUMBING"
HDL_TAP"TRUE";
"B \NAC \NWC"2;
"S \NAC"
BN"0"135;
%"TAP"
"1","(-3225,4050)","0","mstr_standard","I196";
;
CDS_LIB"mstr_standard"
BODY_TYPE"PLUMBING"
HDL_TAP"TRUE";
"B \NAC \NWC"2;
"S \NAC"
BN"1"124;
%"TAP"
"1","(-3225,4000)","0","mstr_standard","I197";
;
CDS_LIB"mstr_standard"
BODY_TYPE"PLUMBING"
HDL_TAP"TRUE";
"B \NAC \NWC"2;
"S \NAC"
BN"2"122;
%"TAP"
"1","(-3225,3950)","0","mstr_standard","I198";
;
CDS_LIB"mstr_standard"
BODY_TYPE"PLUMBING"
HDL_TAP"TRUE";
"B \NAC \NWC"2;
"S \NAC"
BN"3"120;
%"TAP"
"1","(-3225,3850)","0","mstr_standard","I199";
;
CDS_LIB"mstr_standard"
BODY_TYPE"PLUMBING"
HDL_TAP"TRUE";
"B \NAC \NWC"2;
"S \NAC"
BN"5"116;
%"TAP"
"1","(-3225,3900)","0","mstr_standard","I200";
;
CDS_LIB"mstr_standard"
BODY_TYPE"PLUMBING"
HDL_TAP"TRUE";
"B \NAC \NWC"2;
"S \NAC"
BN"4"118;
%"TAP"
"1","(-3225,3800)","0","mstr_standard","I201";
;
CDS_LIB"mstr_standard"
BODY_TYPE"PLUMBING"
HDL_TAP"TRUE";
"B \NAC \NWC"2;
"S \NAC"
BN"6"114;
%"TAP"
"1","(-3225,3750)","0","mstr_standard","I202";
;
CDS_LIB"mstr_standard"
BODY_TYPE"PLUMBING"
HDL_TAP"TRUE";
"B \NAC \NWC"2;
"S \NAC"
BN"7"112;
%"TAP"
"1","(-3225,3600)","0","mstr_standard","I203";
;
CDS_LIB"mstr_standard"
BODY_TYPE"PLUMBING"
HDL_TAP"TRUE";
"B \NAC \NWC"2;
"S \NAC"
BN"9"108;
%"TAP"
"1","(-3225,3650)","0","mstr_standard","I204";
;
CDS_LIB"mstr_standard"
BODY_TYPE"PLUMBING"
HDL_TAP"TRUE";
"B \NAC \NWC"2;
"S \NAC"
BN"8"110;
%"TAP"
"1","(-3225,3550)","0","mstr_standard","I205";
;
CDS_LIB"mstr_standard"
BODY_TYPE"PLUMBING"
HDL_TAP"TRUE";
"B \NAC \NWC"2;
"S \NAC"
BN"10"125;
%"TAP"
"1","(-3225,3500)","0","mstr_standard","I206";
;
CDS_LIB"mstr_standard"
BODY_TYPE"PLUMBING"
HDL_TAP"TRUE";
"B \NAC \NWC"2;
"S \NAC"
BN"11"123;
%"TAP"
"1","(-3225,3450)","0","mstr_standard","I207";
;
CDS_LIB"mstr_standard"
BODY_TYPE"PLUMBING"
HDL_TAP"TRUE";
"B \NAC \NWC"2;
"S \NAC"
BN"12"121;
%"TAP"
"1","(-3225,3350)","0","mstr_standard","I208";
;
CDS_LIB"mstr_standard"
BODY_TYPE"PLUMBING"
HDL_TAP"TRUE";
"B \NAC \NWC"2;
"S \NAC"
BN"14"117;
%"TAP"
"1","(-3225,3400)","0","mstr_standard","I209";
;
CDS_LIB"mstr_standard"
BODY_TYPE"PLUMBING"
HDL_TAP"TRUE";
"B \NAC \NWC"2;
"S \NAC"
BN"13"119;
%"TAP"
"1","(-3225,3300)","0","mstr_standard","I210";
;
CDS_LIB"mstr_standard"
BODY_TYPE"PLUMBING"
HDL_TAP"TRUE";
"B \NAC \NWC"2;
"S \NAC"
BN"15"115;
%"TAP"
"1","(-3225,3200)","0","mstr_standard","I211";
;
CDS_LIB"mstr_standard"
BODY_TYPE"PLUMBING"
HDL_TAP"TRUE";
"B \NAC \NWC"2;
"S \NAC"
BN"16"113;
%"TAP"
"1","(-3225,3150)","0","mstr_standard","I212";
;
CDS_LIB"mstr_standard"
BODY_TYPE"PLUMBING"
HDL_TAP"TRUE";
"B \NAC \NWC"2;
"S \NAC"
BN"17"111;
%"TAP"
"1","(-3225,3100)","0","mstr_standard","I213";
;
CDS_LIB"mstr_standard"
BODY_TYPE"PLUMBING"
HDL_TAP"TRUE";
"B \NAC \NWC"2;
"S \NAC"
BN"18"109;
%"TAP"
"1","(-3225,3050)","0","mstr_standard","I214";
;
CDS_LIB"mstr_standard"
BODY_TYPE"PLUMBING"
HDL_TAP"TRUE";
"B \NAC \NWC"2;
"S \NAC"
BN"19"107;
%"TAP"
"1","(-3225,2950)","0","mstr_standard","I215";
;
CDS_LIB"mstr_standard"
BODY_TYPE"PLUMBING"
HDL_TAP"TRUE";
"B \NAC \NWC"2;
"S \NAC"
BN"21"97;
%"TAP"
"1","(-3225,3000)","0","mstr_standard","I216";
;
CDS_LIB"mstr_standard"
BODY_TYPE"PLUMBING"
HDL_TAP"TRUE";
"B \NAC \NWC"2;
"S \NAC"
BN"20"98;
%"TAP"
"1","(-3225,2900)","0","mstr_standard","I217";
;
CDS_LIB"mstr_standard"
BODY_TYPE"PLUMBING"
HDL_TAP"TRUE";
"B \NAC \NWC"2;
"S \NAC"
BN"22"96;
%"TAP"
"1","(-3225,2850)","0","mstr_standard","I218";
;
CDS_LIB"mstr_standard"
BODY_TYPE"PLUMBING"
HDL_TAP"TRUE";
"B \NAC \NWC"2;
"S \NAC"
BN"23"95;
%"TAP"
"1","(-3225,2750)","0","mstr_standard","I219";
;
CDS_LIB"mstr_standard"
BODY_TYPE"PLUMBING"
HDL_TAP"TRUE";
"B \NAC \NWC"2;
"S \NAC"
BN"24"94;
%"TAP"
"1","(-3225,2700)","0","mstr_standard","I220";
;
CDS_LIB"mstr_standard"
BODY_TYPE"PLUMBING"
HDL_TAP"TRUE";
"B \NAC \NWC"2;
"S \NAC"
BN"25"93;
%"TAP"
"1","(-3225,2650)","0","mstr_standard","I221";
;
CDS_LIB"mstr_standard"
BODY_TYPE"PLUMBING"
HDL_TAP"TRUE";
"B \NAC \NWC"2;
"S \NAC"
BN"26"92;
%"TAP"
"1","(-3225,2600)","0","mstr_standard","I222";
;
CDS_LIB"mstr_standard"
BODY_TYPE"PLUMBING"
HDL_TAP"TRUE";
"B \NAC \NWC"2;
"S \NAC"
BN"27"91;
%"TAP"
"1","(-3225,2500)","0","mstr_standard","I223";
;
CDS_LIB"mstr_standard"
BODY_TYPE"PLUMBING"
HDL_TAP"TRUE";
"B \NAC \NWC"2;
"S \NAC"
BN"29"89;
%"TAP"
"1","(-3225,2550)","0","mstr_standard","I224";
;
CDS_LIB"mstr_standard"
BODY_TYPE"PLUMBING"
HDL_TAP"TRUE";
"B \NAC \NWC"2;
"S \NAC"
BN"28"90;
%"TAP"
"1","(-3225,2450)","0","mstr_standard","I225";
;
CDS_LIB"mstr_standard"
BODY_TYPE"PLUMBING"
HDL_TAP"TRUE";
"B \NAC \NWC"2;
"S \NAC"
BN"30"101;
%"TAP"
"1","(-3225,2400)","0","mstr_standard","I226";
;
CDS_LIB"mstr_standard"
BODY_TYPE"PLUMBING"
HDL_TAP"TRUE";
"B \NAC \NWC"2;
"S \NAC"
BN"31"99;
%"TAP"
"1","(-3225,2300)","0","mstr_standard","I227";
;
CDS_LIB"mstr_standard"
BODY_TYPE"PLUMBING"
HDL_TAP"TRUE";
"B \NAC \NWC"3;
"S \NAC"
BN"0"106;
%"TAP"
"1","(-3225,2250)","0","mstr_standard","I228";
;
CDS_LIB"mstr_standard"
BODY_TYPE"PLUMBING"
HDL_TAP"TRUE";
"B \NAC \NWC"3;
"S \NAC"
BN"1"105;
%"TAP"
"1","(-3225,2200)","0","mstr_standard","I229";
;
CDS_LIB"mstr_standard"
BODY_TYPE"PLUMBING"
HDL_TAP"TRUE";
"B \NAC \NWC"3;
"S \NAC"
BN"2"104;
%"TAP"
"1","(-3225,2150)","0","mstr_standard","I230";
;
CDS_LIB"mstr_standard"
BODY_TYPE"PLUMBING"
HDL_TAP"TRUE";
"B \NAC \NWC"3;
"S \NAC"
BN"3"103;
%"TAP"
"1","(-3225,2100)","0","mstr_standard","I231";
;
CDS_LIB"mstr_standard"
BODY_TYPE"PLUMBING"
HDL_TAP"TRUE";
"B \NAC \NWC"3;
"S \NAC"
BN"4"102;
%"TAP"
"1","(-3225,2050)","0","mstr_standard","I232";
;
CDS_LIB"mstr_standard"
BODY_TYPE"PLUMBING"
HDL_TAP"TRUE";
"B \NAC \NWC"3;
"S \NAC"
BN"5"100;
%"TAP"
"1","(-3225,2000)","0","mstr_standard","I234";
;
CDS_LIB"mstr_standard"
BODY_TYPE"PLUMBING"
HDL_TAP"TRUE";
"B \NAC \NWC"3;
"S \NAC"
BN"6"87;
%"TAP"
"1","(-3225,1950)","0","mstr_standard","I235";
;
CDS_LIB"mstr_standard"
BODY_TYPE"PLUMBING"
HDL_TAP"TRUE";
"B \NAC \NWC"3;
"S \NAC"
BN"7"85;
%"TAP"
"1","(-3225,1800)","0","mstr_standard","I236";
;
CDS_LIB"mstr_standard"
BODY_TYPE"PLUMBING"
HDL_TAP"TRUE";
"B \NAC \NWC"4;
"S \NAC"
BN"1"86;
%"TAP"
"1","(-3225,1850)","0","mstr_standard","I237";
;
CDS_LIB"mstr_standard"
BODY_TYPE"PLUMBING"
HDL_TAP"TRUE";
"B \NAC \NWC"4;
"S \NAC"
BN"0"88;
%"TAP"
"1","(-3225,1750)","0","mstr_standard","I238";
;
CDS_LIB"mstr_standard"
BODY_TYPE"PLUMBING"
HDL_TAP"TRUE";
"B \NAC \NWC"4;
"S \NAC"
BN"2"84;
%"TAP"
"1","(-3225,1700)","0","mstr_standard","I239";
;
CDS_LIB"mstr_standard"
BODY_TYPE"PLUMBING"
HDL_TAP"TRUE";
"B \NAC \NWC"4;
"S \NAC"
BN"3"83;
%"TAP"
"1","(-3225,1600)","0","mstr_standard","I240";
;
CDS_LIB"mstr_standard"
BODY_TYPE"PLUMBING"
HDL_TAP"TRUE";
"B \NAC \NWC"4;
"S \NAC"
BN"5"81;
%"TAP"
"1","(-3225,1650)","0","mstr_standard","I241";
;
CDS_LIB"mstr_standard"
BODY_TYPE"PLUMBING"
HDL_TAP"TRUE";
"B \NAC \NWC"4;
"S \NAC"
BN"4"82;
%"TAP"
"1","(-3225,1550)","0","mstr_standard","I242";
;
CDS_LIB"mstr_standard"
BODY_TYPE"PLUMBING"
HDL_TAP"TRUE";
"B \NAC \NWC"4;
"S \NAC"
BN"6"80;
%"TAP"
"1","(-3225,1500)","0","mstr_standard","I243";
;
CDS_LIB"mstr_standard"
BODY_TYPE"PLUMBING"
HDL_TAP"TRUE";
"B \NAC \NWC"4;
"S \NAC"
BN"7"79;
%"TAP"
"1","(-5650,5900)","2","mstr_standard","I244";
;
CDS_LIB"mstr_standard"
BODY_TYPE"PLUMBING"
HDL_TAP"TRUE";
"B \NAC \NWC"5;
"S \NAC"
BN"0"78;
%"TAP"
"1","(-5650,5800)","2","mstr_standard","I245";
;
CDS_LIB"mstr_standard"
BODY_TYPE"PLUMBING"
HDL_TAP"TRUE";
"B \NAC \NWC"5;
"S \NAC"
BN"1"77;
%"TAP"
"1","(-5650,5700)","2","mstr_standard","I246";
;
CDS_LIB"mstr_standard"
BODY_TYPE"PLUMBING"
HDL_TAP"TRUE";
"B \NAC \NWC"5;
"S \NAC"
BN"2"76;
%"TAP"
"1","(-5650,5600)","2","mstr_standard","I247";
;
CDS_LIB"mstr_standard"
BODY_TYPE"PLUMBING"
HDL_TAP"TRUE";
"B \NAC \NWC"5;
"S \NAC"
BN"3"75;
%"TAP"
"1","(-5650,5400)","2","mstr_standard","I248";
;
CDS_LIB"mstr_standard"
BODY_TYPE"PLUMBING"
HDL_TAP"TRUE";
"B \NAC \NWC"5;
"S \NAC"
BN"5"73;
%"TAP"
"1","(-5650,5500)","2","mstr_standard","I249";
;
CDS_LIB"mstr_standard"
BODY_TYPE"PLUMBING"
HDL_TAP"TRUE";
"B \NAC \NWC"5;
"S \NAC"
BN"4"74;
%"TAP"
"1","(-5650,5300)","2","mstr_standard","I250";
;
CDS_LIB"mstr_standard"
BODY_TYPE"PLUMBING"
HDL_TAP"TRUE";
"B \NAC \NWC"5;
"S \NAC"
BN"6"72;
%"TAP"
"1","(-5650,5200)","2","mstr_standard","I251";
;
CDS_LIB"mstr_standard"
BODY_TYPE"PLUMBING"
HDL_TAP"TRUE";
"B \NAC \NWC"5;
"S \NAC"
BN"7"71;
%"TAP"
"1","(-5850,5750)","2","mstr_standard","I252";
;
CDS_LIB"mstr_standard"
BODY_TYPE"PLUMBING"
HDL_TAP"TRUE";
"B \NAC \NWC"6;
"S \NAC"
BN"1"69;
%"TAP"
"1","(-5850,5850)","2","mstr_standard","I253";
;
CDS_LIB"mstr_standard"
BODY_TYPE"PLUMBING"
HDL_TAP"TRUE";
"B \NAC \NWC"6;
"S \NAC"
BN"0"70;
%"TAP"
"1","(-5850,5650)","2","mstr_standard","I254";
;
CDS_LIB"mstr_standard"
BODY_TYPE"PLUMBING"
HDL_TAP"TRUE";
"B \NAC \NWC"6;
"S \NAC"
BN"2"68;
%"TAP"
"1","(-5850,5550)","2","mstr_standard","I255";
;
CDS_LIB"mstr_standard"
BODY_TYPE"PLUMBING"
HDL_TAP"TRUE";
"B \NAC \NWC"6;
"S \NAC"
BN"3"67;
%"TAP"
"1","(-5850,5450)","2","mstr_standard","I256";
;
CDS_LIB"mstr_standard"
BODY_TYPE"PLUMBING"
HDL_TAP"TRUE";
"B \NAC \NWC"6;
"S \NAC"
BN"4"66;
%"TAP"
"1","(-5850,5350)","2","mstr_standard","I257";
;
CDS_LIB"mstr_standard"
BODY_TYPE"PLUMBING"
HDL_TAP"TRUE";
"B \NAC \NWC"6;
"S \NAC"
BN"5"65;
%"TAP"
"1","(-5850,5250)","2","mstr_standard","I258";
;
CDS_LIB"mstr_standard"
BODY_TYPE"PLUMBING"
HDL_TAP"TRUE";
"B \NAC \NWC"6;
"S \NAC"
BN"6"64;
%"TAP"
"1","(-5850,5150)","2","mstr_standard","I259";
;
CDS_LIB"mstr_standard"
BODY_TYPE"PLUMBING"
HDL_TAP"TRUE";
"B \NAC \NWC"6;
"S \NAC"
BN"7"63;
%"TAP"
"1","(-5650,5100)","2","mstr_standard","I260";
;
CDS_LIB"mstr_standard"
BODY_TYPE"PLUMBING"
HDL_TAP"TRUE";
"B \NAC \NWC"5;
"S \NAC"
BN"8"61;
%"TAP"
"1","(-5650,5000)","2","mstr_standard","I261";
;
CDS_LIB"mstr_standard"
BODY_TYPE"PLUMBING"
HDL_TAP"TRUE";
"B \NAC \NWC"5;
"S \NAC"
BN"9"60;
%"TAP"
"1","(-5650,4850)","2","mstr_standard","I262";
;
CDS_LIB"mstr_standard"
BODY_TYPE"PLUMBING"
HDL_TAP"TRUE";
"B \NAC \NWC"7;
"S \NAC"
BN"0"59;
%"TAP"
"1","(-5650,4750)","2","mstr_standard","I263";
;
CDS_LIB"mstr_standard"
BODY_TYPE"PLUMBING"
HDL_TAP"TRUE";
"B \NAC \NWC"7;
"S \NAC"
BN"1"58;
%"TAP"
"1","(-5650,4650)","2","mstr_standard","I264";
;
CDS_LIB"mstr_standard"
BODY_TYPE"PLUMBING"
HDL_TAP"TRUE";
"B \NAC \NWC"7;
"S \NAC"
BN"2"62;
%"TAP"
"1","(-5650,4550)","2","mstr_standard","I265";
;
CDS_LIB"mstr_standard"
BODY_TYPE"PLUMBING"
HDL_TAP"TRUE";
"B \NAC \NWC"7;
"S \NAC"
BN"3"57;
%"TAP"
"1","(-5650,4450)","2","mstr_standard","I266";
;
CDS_LIB"mstr_standard"
BODY_TYPE"PLUMBING"
HDL_TAP"TRUE";
"B \NAC \NWC"7;
"S \NAC"
BN"4"56;
%"TAP"
"1","(-5650,4250)","2","mstr_standard","I267";
;
CDS_LIB"mstr_standard"
BODY_TYPE"PLUMBING"
HDL_TAP"TRUE";
"B \NAC \NWC"7;
"S \NAC"
BN"6"54;
%"TAP"
"1","(-5650,4350)","2","mstr_standard","I268";
;
CDS_LIB"mstr_standard"
BODY_TYPE"PLUMBING"
HDL_TAP"TRUE";
"B \NAC \NWC"7;
"S \NAC"
BN"5"55;
%"TAP"
"1","(-5650,4150)","2","mstr_standard","I269";
;
CDS_LIB"mstr_standard"
BODY_TYPE"PLUMBING"
HDL_TAP"TRUE";
"B \NAC \NWC"7;
"S \NAC"
BN"7"53;
%"TAP"
"1","(-5850,4950)","2","mstr_standard","I270";
;
CDS_LIB"mstr_standard"
BODY_TYPE"PLUMBING"
HDL_TAP"TRUE";
"B \NAC \NWC"6;
"S \NAC"
BN"9"45;
%"TAP"
"1","(-5850,5050)","2","mstr_standard","I271";
;
CDS_LIB"mstr_standard"
BODY_TYPE"PLUMBING"
HDL_TAP"TRUE";
"B \NAC \NWC"6;
"S \NAC"
BN"8"47;
%"TAP"
"1","(-5850,4800)","2","mstr_standard","I272";
;
CDS_LIB"mstr_standard"
BODY_TYPE"PLUMBING"
HDL_TAP"TRUE";
"B \NAC \NWC"8;
"S \NAC"
BN"0"50;
%"TAP"
"1","(-5850,4700)","2","mstr_standard","I273";
;
CDS_LIB"mstr_standard"
BODY_TYPE"PLUMBING"
HDL_TAP"TRUE";
"B \NAC \NWC"8;
"S \NAC"
BN"1"49;
%"TAP"
"1","(-5850,4600)","2","mstr_standard","I274";
;
CDS_LIB"mstr_standard"
BODY_TYPE"PLUMBING"
HDL_TAP"TRUE";
"B \NAC \NWC"8;
"S \NAC"
BN"2"48;
%"TAP"
"1","(-5850,4500)","2","mstr_standard","I275";
;
CDS_LIB"mstr_standard"
BODY_TYPE"PLUMBING"
HDL_TAP"TRUE";
"B \NAC \NWC"8;
"S \NAC"
BN"3"46;
%"TAP"
"1","(-5850,4400)","2","mstr_standard","I276";
;
CDS_LIB"mstr_standard"
BODY_TYPE"PLUMBING"
HDL_TAP"TRUE";
"B \NAC \NWC"8;
"S \NAC"
BN"4"44;
%"TAP"
"1","(-5850,4200)","2","mstr_standard","I277";
;
CDS_LIB"mstr_standard"
BODY_TYPE"PLUMBING"
HDL_TAP"TRUE";
"B \NAC \NWC"8;
"S \NAC"
BN"6"52;
%"TAP"
"1","(-5850,4300)","2","mstr_standard","I278";
;
CDS_LIB"mstr_standard"
BODY_TYPE"PLUMBING"
HDL_TAP"TRUE";
"B \NAC \NWC"8;
"S \NAC"
BN"5"43;
%"TAP"
"1","(-5850,4100)","2","mstr_standard","I279";
;
CDS_LIB"mstr_standard"
BODY_TYPE"PLUMBING"
HDL_TAP"TRUE";
"B \NAC \NWC"8;
"S \NAC"
BN"7"51;
%"TAP"
"1","(-5650,3950)","2","mstr_standard","I284";
;
CDS_LIB"mstr_standard"
BODY_TYPE"PLUMBING"
HDL_TAP"TRUE";
"B \NAC \NWC"7;
"S \NAC"
BN"9"41;
%"TAP"
"1","(-5650,4050)","2","mstr_standard","I285";
;
CDS_LIB"mstr_standard"
BODY_TYPE"PLUMBING"
HDL_TAP"TRUE";
"B \NAC \NWC"7;
"S \NAC"
BN"8"42;
%"TAP"
"1","(-5850,4000)","2","mstr_standard","I286";
;
CDS_LIB"mstr_standard"
BODY_TYPE"PLUMBING"
HDL_TAP"TRUE";
"B \NAC \NWC"8;
"S \NAC"
BN"8"36;
%"TAP"
"1","(-5850,3900)","2","mstr_standard","I287";
;
CDS_LIB"mstr_standard"
BODY_TYPE"PLUMBING"
HDL_TAP"TRUE";
"B \NAC \NWC"8;
"S \NAC"
BN"9"33;
%"TAP"
"1","(-5850,3600)","2","mstr_standard","I288";
;
CDS_LIB"mstr_standard"
BODY_TYPE"PLUMBING"
HDL_TAP"TRUE";
"B \NAC \NWC"10;
"S \NAC"
BN"3"34;
%"TAP"
"1","(-5850,3750)","2","mstr_standard","I289";
;
CDS_LIB"mstr_standard"
BODY_TYPE"PLUMBING"
HDL_TAP"TRUE";
"B \NAC \NWC"10;
"S \NAC"
BN"0"26;
%"TAP"
"1","(-5850,3700)","2","mstr_standard","I290";
;
CDS_LIB"mstr_standard"
BODY_TYPE"PLUMBING"
HDL_TAP"TRUE";
"B \NAC \NWC"10;
"S \NAC"
BN"1"39;
%"TAP"
"1","(-5850,3650)","2","mstr_standard","I291";
;
CDS_LIB"mstr_standard"
BODY_TYPE"PLUMBING"
HDL_TAP"TRUE";
"B \NAC \NWC"10;
"S \NAC"
BN"2"37;
%"TAP"
"1","(-5850,3350)","2","mstr_standard","I292";
;
CDS_LIB"mstr_standard"
BODY_TYPE"PLUMBING"
HDL_TAP"TRUE";
"B \NAC \NWC"9;
"S \NAC"
BN"0"40;
%"TAP"
"1","(-5850,3550)","2","mstr_standard","I293";
;
CDS_LIB"mstr_standard"
BODY_TYPE"PLUMBING"
HDL_TAP"TRUE";
"B \NAC \NWC"10;
"S \NAC"
BN"4"31;
%"TAP"
"1","(-5850,3450)","2","mstr_standard","I294";
;
CDS_LIB"mstr_standard"
BODY_TYPE"PLUMBING"
HDL_TAP"TRUE";
"B \NAC \NWC"10;
"S \NAC"
BN"6"27;
%"TAP"
"1","(-5850,3500)","2","mstr_standard","I295";
;
CDS_LIB"mstr_standard"
BODY_TYPE"PLUMBING"
HDL_TAP"TRUE";
"B \NAC \NWC"10;
"S \NAC"
BN"5"29;
%"TAP"
"1","(-5850,3250)","2","mstr_standard","I296";
;
CDS_LIB"mstr_standard"
BODY_TYPE"PLUMBING"
HDL_TAP"TRUE";
"B \NAC \NWC"9;
"S \NAC"
BN"2"35;
%"TAP"
"1","(-5850,3300)","2","mstr_standard","I297";
;
CDS_LIB"mstr_standard"
BODY_TYPE"PLUMBING"
HDL_TAP"TRUE";
"B \NAC \NWC"9;
"S \NAC"
BN"1"38;
%"TAP"
"1","(-5850,3200)","2","mstr_standard","I298";
;
CDS_LIB"mstr_standard"
BODY_TYPE"PLUMBING"
HDL_TAP"TRUE";
"B \NAC \NWC"9;
"S \NAC"
BN"3"32;
%"TAP"
"1","(-5850,3150)","2","mstr_standard","I299";
;
CDS_LIB"mstr_standard"
BODY_TYPE"PLUMBING"
HDL_TAP"TRUE";
"B \NAC \NWC"9;
"S \NAC"
BN"4"30;
%"TAP"
"1","(-5850,3100)","2","mstr_standard","I300";
;
CDS_LIB"mstr_standard"
BODY_TYPE"PLUMBING"
HDL_TAP"TRUE";
"B \NAC \NWC"9;
"S \NAC"
BN"5"28;
%"TAP"
"1","(-5850,3050)","2","mstr_standard","I301";
;
CDS_LIB"mstr_standard"
BODY_TYPE"PLUMBING"
HDL_TAP"TRUE";
"B \NAC \NWC"9;
"S \NAC"
BN"6"25;
%"Q_RES"
"1","(-6525,2050)","0","pure_quanta","I314";
;
LOCATION"R510"
$SEC"1"
CDS_SEC"1"
PACK_TYPE"0402LF"
TOLERANCE"1%"
VALUE"15"
MATERIAL"CHIP"
WATTAGE"1/16W"
CDS_LIB"pure_quanta"
PART_NUMBER"CS01502FB03";
"B"
$PN"2"12;
"A"
$PN"1"11;
END.
